# S9S_MB_2U (Grand Teton) — schematic netlist excerpt (pin names and nets, part order shuffled) for the footprints in the layout excerpt that follows; sources: Cadence DE-HDL packaged netlist, KiCad conversion of 03242023_DA0F0TMBIJ0_F0T_Motherboard_J_brd_V01_OCP.brd

R4510  Q_RES  33.2 1% CHIP  pkg 0402LF  page 241 : A = SMB_HOST_3V3AUX_SCL ; B = SMB_HOST_3V3AUX_SCL_R4

(kicad_pcb
	(version 20260206)
	(generator "pcbnew")
	(generator_version "10.0")
	(general
		(thickness 1.6)
		(legacy_teardrops no)
	)
	(paper "A4")
	(title_block
		(title "03242023_DA0F0TMBIJ0_F0T_Motherboard_J_brd_V01_OCP.brd")
		(comment 1 "Grand Teton / footprints 4715-4715 of 6105")
	)
	(layers
		(0 "F.Cu" signal "TOP")
		(4 "In1.Cu" signal "GND")
		(6 "In2.Cu" signal "IN1")
		(8 "In3.Cu" signal "GND1")
		(10 "In4.Cu" signal "IN2")
		(12 "In5.Cu" signal "GND2")
		(14 "In6.Cu" signal "IN3")
		(16 "In7.Cu" signal "GND3")
		(18 "In8.Cu" signal "VCC")
		(20 "In9.Cu" signal "VCC1")
		(22 "In10.Cu" signal "GND4")
		(24 "In11.Cu" signal "IN4")
		(26 "In12.Cu" signal "GND5")
		(28 "In13.Cu" signal "IN5")
		(30 "In14.Cu" signal "GND6")
		(32 "In15.Cu" signal "IN6")
		(34 "In16.Cu" signal "GND7")
		(2 "B.Cu" signal "BOTTOM")
		(9 "F.Adhes" user "F.Adhesive")
		(11 "B.Adhes" user "B.Adhesive")
		(13 "F.Paste" user "Package Geometry/Pastemask Top")
		(15 "B.Paste" user "Package Geometry/Pastemask Bottom")
		(5 "F.SilkS" user "Ref Des/Silkscreen Top")
		(7 "B.SilkS" user "Ref Des/Silkscreen Bottom")
		(1 "F.Mask" user "Board Geometry/Soldermask Top")
		(3 "B.Mask" user "Board Geometry/Soldermask Bottom")
		(17 "Dwgs.User" user "User.Drawings")
		(19 "Cmts.User" user "User.Comments")
		(21 "Eco1.User" user "User.Eco1")
		(23 "Eco2.User" user "User.Eco2")
		(25 "Edge.Cuts" user "Board Geometry/Outline")
		(27 "Margin" user)
		(31 "F.CrtYd" user "Package Geometry/Place Bound Top")
		(29 "B.CrtYd" user "Package Geometry/Place Bound Bottom")
		(35 "F.Fab" user "Ref Des/Assembly Top")
		(33 "B.Fab" user "Ref Des/Assembly Bottom")
	)
	(footprint ""
		(layer "B.Cu")
		(at 236.76991 -130.072892)
		(property "Reference" "R4510"
			(at 0 0 0)
			(layer "B.SilkS")
			(hide yes)
			(effects
				(font
					(size 1.27 1.27)
				)
				(justify mirror)
			)
		)
		(property "Value" ""
			(at 0 0 0)
			(layer "B.Fab")
			(effects
				(font
					(size 1.27 1.27)
				)
				(justify mirror)
			)
		)
		(duplicate_pad_numbers_are_jumpers no)
		(fp_line
			(start -0.7874 -0.4064)
			(end -0.7874 0.4064)
			(stroke
				(width 0.1524)
				(type default)
			)
			(layer "B.SilkS")
		)
		(fp_line
			(start -0.7874 0.4064)
			(end 0.7874 0.4064)
			(stroke
				(width 0.1524)
				(type default)
			)
			(layer "B.SilkS")
		)
		(fp_line
			(start 0.7874 -0.4064)
			(end -0.7874 -0.4064)
			(stroke
				(width 0.1524)
				(type default)
			)
			(layer "B.SilkS")
		)
		(fp_line
			(start 0.7874 0.4064)
			(end 0.7874 -0.4064)
			(stroke
				(width 0.1524)
				(type default)
			)
			(layer "B.SilkS")
		)
		(fp_line
			(start -0.67945 -0.3048)
			(end -0.67945 0.3048)
			(stroke
				(width 0.1)
				(type default)
			)
			(layer "B.Fab")
		)
		(fp_line
			(start -0.67945 0.3048)
			(end -0.120396 0.3048)
			(stroke
				(width 0.1)
				(type default)
			)
			(layer "B.Fab")
		)
		(fp_line
			(start -0.12065 -0.3048)
			(end -0.67945 -0.3048)
			(stroke
				(width 0.1)
				(type default)
			)
			(layer "B.Fab")
		)
		(fp_line
			(start -0.12065 -0.2794)
			(end -0.12065 -0.3048)
			(stroke
				(width 0.1)
				(type default)
			)
			(layer "B.Fab")
		)
		(fp_line
			(start -0.120396 0.2794)
			(end 0.12065 0.2794)
			(stroke
				(width 0.1)
				(type default)
			)
			(layer "B.Fab")
		)
		(fp_line
			(start -0.120396 0.3048)
			(end -0.120396 0.2794)
			(stroke
				(width 0.1)
				(type default)
			)
			(layer "B.Fab")
		)
		(fp_line
			(start 0.12065 -0.305054)
			(end 0.12065 -0.2794)
			(stroke
				(width 0.1)
				(type default)
			)
			(layer "B.Fab")
		)
		(fp_line
			(start 0.12065 -0.2794)
			(end -0.12065 -0.2794)
			(stroke
				(width 0.1)
				(type default)
			)
			(layer "B.Fab")
		)
		(fp_line
			(start 0.12065 0.2794)
			(end 0.12065 0.3048)
			(stroke
				(width 0.1)
				(type default)
			)
			(layer "B.Fab")
		)
		(fp_line
			(start 0.12065 0.3048)
			(end 0.67945 0.3048)
			(stroke
				(width 0.1)
				(type default)
			)
			(layer "B.Fab")
		)
		(fp_line
			(start 0.67945 -0.305054)
			(end 0.12065 -0.305054)
			(stroke
				(width 0.1)
				(type default)
			)
			(layer "B.Fab")
		)
		(fp_line
			(start 0.67945 0.3048)
			(end 0.67945 -0.305054)
			(stroke
				(width 0.1)
				(type default)
			)
			(layer "B.Fab")
		)
		(pad "1" smd circle
			(at 0.40005 0 180)
			(size 0 0)
			(layers "B.Cu" "B.Mask" "B.Paste")
			(net "SMB_HOST_3V3AUX_SCL")
		)
		(pad "2" smd circle
			(at -0.40005 0 180)
			(size 0 0)
			(layers "B.Cu" "B.Mask" "B.Paste")
			(net "SMB_HOST_3V3AUX_SCL_R4")
		)
	)
)
